FILE_TYPE = CONNECTIVITY;
{Allegro Design Entry HDL 17.2-2016 S081 (4005846) 1/11/2022}
"PAGE_NUMBER" = 15;
0"NC";
1"PWRGD_PLT_AUX_CPU0_LVT3";
2"TP_FM_IBL_SYS_RST_CPU0_N";
3"TP_CPU0_PWRBTN_N";
4"TP_I2C_S3M_RTC_CPU0_SCL";
5"TP_SPI_IBL_CPU0_TPM_CLK";
6"TP_CPU0_SSC_SYNC";
7"TP_IBL_SLPS4_CPU0_R_N";
8"TP_FM_IBL_ADR_ACK_CPU0";
9"TP_ESPI_IBL_CPU0_IO2_LVC1";
10"TP_JTAG_CPU0_PLD_TDO";
11"TP_FM_IBL_ADR_COMPLETE_CPU0_R";
12"TP_IBL_SLPS3_CPU0_R_N";
13"TP_JTAG_CPU0_PLD_TDI";
14"TP_FM_IBL_ADR_TRIGGER_CPU0_R";
15"TP_JTAG_CPU0_PLD_TMS";
16"NC_UART_IBL_CPU0_TXD";
17"NC_UART_IBL_CPU0_CTS";
18"TP_IBL_SLPS5_CPU0_R_N";
19"FM_S3M_CPU0_CPLD_CRC_ERROR";
20"PD_JTAG_CPU0_PLD_TCK";
21"NC_UART_IBL_CPU0_RXD";
22"NC_UART_IBL_CPU0_RTS";
23"TP_SPI_S3M_CPU0_CS1_LVC1_R_N";
24"TP_FM_IBL_WAKE_CPU0_N";
25"TP_SPI_S3M_CPU0_IO1_LVC1_R";
26"TP_SPI_IBL_CPU0_TPM_IO1";
27"TP_SPI_IBL_CPU0_TPM_CS0_N";
28"TP_SPI_S3M_CPU0_IO0_LVC1_R";
29"TP_SPI_IBL_CPU0_TPM_IO0";
30"TP_SPI_S3M_CPU0_OE_LVC1_R_N";
31"TP_SPI_S3M_CPU0_CS0_LVC1_R_N";
32"TP_SPI_IBL_CPU0_TPM_OE_N";
33"TP_I3C_MNG2_BMC_SW_SDA";
34"TP_SPI_S3M_CPU0_CLK_LVC1_R";
35"TP_SPI_S3M_CPU0_IO3_LVC1_R";
36"TP_ESPI_IBL_CPU0_ALERT1_N";
37"TP_SPI_S3M_CPU0_IO2_LVC1_R";
38"TP_I3C_MNG2_BMC_SW_SCL";
39"TP_ESPI_IBL_CPU0_ALERT0_LVC1_N";
40"TP_ESPI_IBL_CPU0_CS0_LVC1_N";
41"TP_CLK_66M_ESPI_IBL_CPU0_LVC1";
42"TP_RST_ESPI_IBL_CPU0_LVC1_N";
43"TP_ESPI_IBL_CPU0_OE_LVC1_N";
44"TP_ESPI_IBL_CPU0_CS1_N";
45"TP_ESPI_IBL_CPU0_IO1_LVC1";
46"TP_ESPI_IBL_CPU0_IO0_LVC1";
47"TP_ESPI_IBL_CPU0_IO3_LVC1";
48"TP_SGPIO_S3M_CPU0_RST_R_N";
49"PUD_PCH_BOOT_MODE_CPU0";
50"TP_SGPIO_S3M_CPU0_GSXCLK_R";
51"TP_SGPIO_S3M_CPU0_GSXDOUT_R";
52"TP_SGPIO_S3M_CPU0_GSXDIN";
53"TP_PWRGD_S0_PWROK_CPU0_LVC1";
54"TP_IBL_GRST_WARN_PLD_R_N";
55"TP_I2C_S3M_RTC_CPU0_SDA";
56"TP_I2C_S3M_RTC_CPU0_ALERT_N";
57"TP_SGPIO_S3M_CPU0_GSXDLOAD_R";
58"FM_S3M_CPU0_LVC1_GPIO_4";
59"FM_S3M_CPU0_LVC1_GPIO_3";
60"FM_S3M_CPU0_LVC1_GPIO_2";
61"FM_S3M_CPU0_LVC1_GPIO_1";
62"FM_S3M_CPU0_LVC1_GPIO_0";
63"SMB_S3M_CPU0_SCL";
64"SMB_S3M_CPU0_SDA";
65"PU_S3M_CPU0_CPLD_CONFD";
66"FM_S3M_CPU0_CPLD_CONFIG_N";
67"PU_S3M_CPU0_CPLD_STATUS";
%"SOCKET4677_AZIF0045P001C01CS"
"3","(200,2475)","0","pure_quanta","I1";
;
PART_NUMBER"DGA^7000023"
PART_TYPE"SMLF"
MATERIAL"IO"
VALUE"SOCKET4677_AZIF0045-P001C01CS"
$LOCATION"U2"
CDS_LIB"pure_quanta"
NEEDS_NO_SIZE"TRUE"
CDS_LMAN_SYM_OUTLINE"-1050,1500,1050,-1450"
CDS_LOCATION"U2"
$SEC"3"
CDS_SEC"3";
"TEST_3"
$PN"CH65"67;
"TEST_2"
$PN"CK65"66;
"TEST_1"
$PN"CJ64"65;
"SMB_DATA"
$PN"CD63"64;
"SMB_CLK"
$PN"CE64"63;
"PARTITION_ID0"
$PN"BA70"62;
"PARTITION_ID1"
$PN"AV71"61;
"TEST_7"
$PN"AV69"60;
"TEST_8"
$PN"AY69"59;
"RSVD25"
$PN"AW70"58;
"RSVD105"
$PN"CJ66"57;
"RSVD103"
$PN"CJ25"56;
"RSVD102"
$PN"CJ23"55;
"RSVD101"
$PN"CJ21"54;
"RSVD100"
$PN"CH71"53;
"RSVD98"
$PN"CH63"52;
"RSVD94"
$PN"CF65"51;
"RSVD93"
$PN"CF63"50;
"TEST_6"
$PN"CF61"49;
"RSVD86"
$PN"CD65"48;
"RSVD64"
$PN"BM63"47;
"RSVD61"
$PN"BK63"46;
"RSVD58"
$PN"BJ64"45;
"RSVD56"
$PN"BH65"44;
"RSVD55"
$PN"BH63"43;
"RSVD53"
$PN"BG64"42;
"RSVD52"
$PN"BG62"41;
"RSVD50"
$PN"BF65"40;
"RSVD48"
$PN"BE62"39;
"RSVD47"
$PN"BE25"38;
"RSVD42"
$PN"BD65"37;
"RSVD41"
$PN"BD63"36;
"RSVD40"
$PN"BD61"35;
"RSVD39"
$PN"BC64"34;
"RSVD38"
$PN"BC25"33;
"RSVD36"
$PN"BB67"32;
"RSVD35"
$PN"BB61"31;
"RSVD34"
$PN"BA68"30;
"RSVD33"
$PN"BA66"29;
"RSVD32"
$PN"BA62"28;
"RSVD30"
$PN"AY67"27;
"RSVD28"
$PN"AY61"26;
"RSVD24"
$PN"AW64"25;
"RSVD23"
$PN"AW19"24;
"RSVD20"
$PN"AV63"23;
"RSVD156"
$PN"CY71"22;
"RSVD155"
$PN"CY69"21;
"TEST_5"
$PN"CY22"20;
"CD_INIT_ERROR"
$PN"CY20"19;
"RSVD144"
$PN"CW21"18;
"RSVD143"
$PN"CV71"17;
"RSVD142"
$PN"CV69"16;
"RSVD140"
$PN"CV22"15;
"RSVD137"
$PN"CT24"14;
"RSVD136"
$PN"CT22"13;
"RSVD131"
$PN"CR21"12;
"RSVD128"
$PN"CP24"11;
"RSVD127"
$PN"CP22"10;
"RSVD12"
$PN"AU64"9;
"RSVD124"
$PN"CN23"8;
"RSVD123"
$PN"CN21"7;
"RSVD117"
$PN"CL66"6;
"RSVD11"
$PN"AU62"5;
"RSVD114"
$PN"CL23"4;
"RSVD110"
$PN"CK24"3;
"RSVD109"
$PN"CK22"2;
"PLT_AUX_PWRGOOD"
$PN"CV20"1;
END.
